# BASEBOARD_FAB2 (Tioga Pass) — schematic netlist excerpt (pin names and nets, part order shuffled) for the footprints in the layout excerpt that follows; sources: Cadence DE-HDL packaged netlist, KiCad conversion of Wiwynn_Tioga_Pass_MB.brd

R7P26  RES  49.9 1% CHIP  pkg 0402  page 55 : A = H_PMSYNC_CLK_24M_CPU1 ; B = H_PMSYNC_CLK_24M
R25W28  120R2F-GP  1%  pkg RCL_GP  page 151 : \1\ = BMC_M_ODT ; \2\ = P1V2_AUX_BMC

(kicad_pcb
	(version 20260206)
	(generator "pcbnew")
	(generator_version "10.0")
	(general
		(thickness 1.6)
		(legacy_teardrops no)
	)
	(paper "A4")
	(title_block
		(title "Wiwynn_Tioga_Pass_MB.brd")
		(comment 1 "Tioga Pass / footprints 2761-2762 of 4770")
	)
	(layers
		(0 "F.Cu" signal "TOP")
		(4 "In1.Cu" signal "L2GND")
		(6 "In2.Cu" signal "L3")
		(8 "In3.Cu" signal "L4GND")
		(10 "In4.Cu" signal "L5")
		(12 "In5.Cu" signal "L6GND")
		(14 "In6.Cu" signal "L7VCC")
		(16 "In7.Cu" signal "L8VCC")
		(18 "In8.Cu" signal "L9GND")
		(20 "In9.Cu" signal "L10")
		(22 "In10.Cu" signal "L11GND")
		(24 "In11.Cu" signal "L12")
		(26 "In12.Cu" signal "L13GND")
		(2 "B.Cu" signal "BOTTOM")
		(9 "F.Adhes" user "F.Adhesive")
		(11 "B.Adhes" user "B.Adhesive")
		(13 "F.Paste" user "Package Geometry/Pastemask Top")
		(15 "B.Paste" user "Package Geometry/Pastemask Bottom")
		(5 "F.SilkS" user "Ref Des/Silkscreen Top")
		(7 "B.SilkS" user "Ref Des/Silkscreen Bottom")
		(1 "F.Mask" user "Board Geometry/Soldermask Top")
		(3 "B.Mask" user "Board Geometry/Soldermask Bottom")
		(17 "Dwgs.User" user "User.Drawings")
		(19 "Cmts.User" user "User.Comments")
		(21 "Eco1.User" user "User.Eco1")
		(23 "Eco2.User" user "User.Eco2")
		(25 "Edge.Cuts" user "Board Geometry/Outline")
		(27 "Margin" user)
		(31 "F.CrtYd" user "Package Geometry/Place Bound Top")
		(29 "B.CrtYd" user "Package Geometry/Place Bound Bottom")
		(35 "F.Fab" user "Ref Des/Assembly Top")
		(33 "B.Fab" user "Ref Des/Assembly Bottom")
	)
	(footprint ""
		(layer "B.Cu")
		(at 448.55638 -33.5915 90)
		(property "Reference" "R25W28"
			(at 0 0 90)
			(layer "B.SilkS")
			(hide yes)
			(effects
				(font
					(size 1.27 1.27)
				)
				(justify mirror)
			)
		)
		(property "Value" "*"
			(at -0.064008 -4.108196 90)
			(unlocked yes)
			(layer "B.Fab")
			(hide yes)
			(effects
				(font
					(size 1.27 1.016)
					(thickness 0.1524)
				)
				(justify mirror)
			)
		)
		(property "Device Type" "120R2F-GP_RCL_GP-120R2F-GP,64.A"
			(at -0.064008 -5.632196 90)
			(unlocked yes)
			(layer "B.Fab")
			(hide yes)
			(effects
				(font
					(size 1.27 1.016)
					(thickness 0.1524)
				)
				(justify mirror)
			)
		)
		(duplicate_pad_numbers_are_jumpers no)
		(fp_line
			(start 0.508 -0.9398)
			(end 0.508 0.9398)
			(stroke
				(width 0.1524)
				(type default)
			)
			(layer "B.SilkS")
		)
		(fp_line
			(start -0.508 -0.9398)
			(end 0.508 -0.9398)
			(stroke
				(width 0.1524)
				(type default)
			)
			(layer "B.SilkS")
		)
		(fp_rect
			(start 0.508 0.9398)
			(end -0.508 -0.9398)
			(stroke
				(width 0)
				(type default)
			)
			(fill no)
			(layer "B.CrtYd")
		)
		(fp_rect
			(start 0.508 0.9398)
			(end -0.508 -0.9398)
			(stroke
				(width 0)
				(type default)
			)
			(fill no)
			(layer "B.Fab")
		)
		(pad "1" smd custom
			(at 0 -0.4445 270)
			(size 0.1397 0.1397)
			(layers "B.Cu" "B.Mask" "B.Paste")
			(net "BMC_M_ODT")
			(options
				(clearance outline)
				(anchor circle)
			)
			(primitives
				(gr_poly
					(pts
						(arc
							(start -0.1778 0.2794)
							(mid -0.249642 0.249642)
							(end -0.2794 0.1778)
						)
						(arc
							(start -0.2794 -0.1778)
							(mid -0.249642 -0.249642)
							(end -0.1778 -0.2794)
						)
						(arc
							(start 0.1778 -0.2794)
							(mid 0.249642 -0.249642)
							(end 0.2794 -0.1778)
						)
						(arc
							(start 0.2794 0.1778)
							(mid 0.249642 0.249642)
							(end 0.1778 0.2794)
						)
					)
					(width 0)
					(fill yes)
				)
			)
		)
		(pad "2" smd custom
			(at 0 0.4445 270)
			(size 0.1397 0.1397)
			(layers "B.Cu" "B.Mask" "B.Paste")
			(net "P1V2_AUX_BMC")
			(options
				(clearance outline)
				(anchor circle)
			)
			(primitives
				(gr_poly
					(pts
						(arc
							(start -0.1778 0.2794)
							(mid -0.249642 0.249642)
							(end -0.2794 0.1778)
						)
						(arc
							(start -0.2794 -0.1778)
							(mid -0.249642 -0.249642)
							(end -0.1778 -0.2794)
						)
						(arc
							(start 0.1778 -0.2794)
							(mid 0.249642 -0.249642)
							(end 0.2794 -0.1778)
						)
						(arc
							(start 0.2794 0.1778)
							(mid 0.249642 0.249642)
							(end 0.1778 0.2794)
						)
					)
					(width 0)
					(fill yes)
				)
			)
		)
	)
	(footprint ""
		(layer "B.Cu")
		(at 129.777998 -67.677538)
		(property "Reference" "R7P26"
			(at 0 0 0)
			(layer "B.SilkS")
			(hide yes)
			(effects
				(font
					(size 1.27 1.27)
				)
				(justify mirror)
			)
		)
		(property "Value" ""
			(at 0 0 0)
			(layer "B.Fab")
			(effects
				(font
					(size 1.27 1.27)
				)
				(justify mirror)
			)
		)
		(duplicate_pad_numbers_are_jumpers no)
		(fp_poly
			(pts
				(xy 0.2794 -0.1016) (xy -0.2794 -0.1016) (xy -0.2794 0.9906) (xy 0.2794 0.9906)
			)
			(stroke
				(width 0)
				(type default)
			)
			(fill no)
			(layer "B.CrtYd")
		)
		(fp_line
			(start -0.2794 -0.1016)
			(end 0.2794 -0.1016)
			(stroke
				(width 0.1)
				(type default)
			)
			(layer "B.Fab")
		)
		(fp_line
			(start -0.2794 0.9906)
			(end -0.2794 -0.1016)
			(stroke
				(width 0.1)
				(type default)
			)
			(layer "B.Fab")
		)
		(fp_line
			(start 0.2794 -0.1016)
			(end 0.2794 0.9906)
			(stroke
				(width 0.1)
				(type default)
			)
			(layer "B.Fab")
		)
		(fp_line
			(start 0.2794 0.9906)
			(end -0.2794 0.9906)
			(stroke
				(width 0.1)
				(type default)
			)
			(layer "B.Fab")
		)
		(pad "1" smd rect
			(at 0 0 180)
			(size 0.508 0.508)
			(layers "B.Cu" "B.Mask" "B.Paste")
			(net "H_PMSYNC_CLK_24M_CPU1")
		)
		(pad "2" smd rect
			(at 0 0.889 180)
			(size 0.508 0.508)
			(layers "B.Cu" "B.Mask" "B.Paste")
			(net "H_PMSYNC_CLK_24M")
		)
		(zone
			(layer "B.Cu")
			(hatch none 0.5)
			(connect_pads
				(clearance 0)
			)
			(min_thickness 0.25)
			(keepout
				(tracks allowed)
				(vias not_allowed)
				(pads allowed)
				(copperpour not_allowed)
				(footprints allowed)
			)
			(placement
				(enabled no)
				(sheetname "")
			)
			(fill
				(thermal_gap 0.5)
				(thermal_bridge_width 0.5)
				(island_removal_mode 0)
			)
			(polygon
				(pts
					(xy 130.031998 -67.423538) (xy 129.523998 -67.423538) (xy 129.523998 -67.042538) (xy 130.031998 -67.042538)
				)
			)
		)
		(zone
			(layer "B.Cu")
			(hatch none 0.5)
			(connect_pads
				(clearance 0)
			)
			(min_thickness 0.25)
			(keepout
				(tracks not_allowed)
				(vias allowed)
				(pads allowed)
				(copperpour not_allowed)
				(footprints allowed)
			)
			(placement
				(enabled no)
				(sheetname "")
			)
			(fill
				(thermal_gap 0.5)
				(thermal_bridge_width 0.5)
				(island_removal_mode 0)
			)
			(polygon
				(pts
					(xy 130.031998 -67.042538) (xy 129.523998 -67.042538) (xy 129.523998 -67.423538) (xy 130.031998 -67.423538)
				)
			)
		)
	)
)
